FILE_TYPE = CONNECTIVITY;
{Allegro Design Entry HDL 17.2-2016 S081 (4005846) 1/11/2022}
"PAGE_NUMBER" = 38;
0"NC";
1"VCCIO4\g";
%"LCMXO3LF2100C5BG256C"
"5","(-4775,4475)","0","pure_quanta","I1";
;
PART_NUMBER"AJ021000T03"
MATERIAL"IC"
PART_TYPE"SMLF"
VALUE"LCMXO3LF-2100C-5BG256C"
CDS_LMAN_SYM_OUTLINE"-500,650,500,-650"
NEEDS_NO_SIZE"TRUE"
CDS_LIB"pure_quanta"
LOCATION"U25"
$SEC"5"
CDS_SEC"5";
"VCCIO4_J7"
$PN"J7"1;
"VCCIO4_H7"
$PN"H7"1;
"PL9D"
$PN"J4"0;
"PL9C"
$PN"H5"0;
"PL9B"
$PN"K1"0;
"PL9A"
$PN"J2"0;
"PL10B"
$PN"K2"0;
"PL10A"
$PN"K3"0;
"PL10D"
$PN"K6"0;
"PL10C"
$PN"J5"0;
"PL7D||PCLKC4_0"
$PN"J3"0;
"PL7C||PCLKT4_0"
$PN"J1"0;
"PL7B"
$PN"H1"0;
"PL7A"
$PN"H3"0;
"PL6D"
$PN"J6"0;
"PL6C"
$PN"H4"0;
"PL6B"
$PN"H2"0;
"PL6A"
$PN"G1"0;
%"UNIVERSAL_POWER"
"1","(-3750,4175)","0","logical_power","I3";
;
HDL_POWER"VCCIO4"
CDS_LIB"logical_power";
"A"1;
END.
